# SCM (Grand Teton) — schematic netlist excerpt (pin names and nets, part order shuffled) for the footprints in the layout excerpt that follows; sources: Cadence DE-HDL packaged netlist, KiCad conversion of 12092022_DA0F0TMDCD0_F0T_Management_Board_D_brd_V3_OCP.brd

R139  Q_RES  33.2 1% CHIP  pkg 0402LF  page 12 : A = SMB_BMC_MM4_R_SDA ; B = SMB_BMC_MM4_SDA
R684  Q_RES  1K 1% EMPTY  pkg 0402LF  page 14 : A = BMC_EMMC_WP_N ; B = GND

(kicad_pcb
	(version 20260206)
	(generator "pcbnew")
	(generator_version "10.0")
	(general
		(thickness 1.6)
		(legacy_teardrops no)
	)
	(paper "A4")
	(title_block
		(title "12092022_DA0F0TMDCD0_F0T_Management_Board_D_brd_V3_OCP.brd")
		(comment 1 "Grand Teton / footprints 1239-1240 of 1440")
	)
	(layers
		(0 "F.Cu" signal "TOP")
		(4 "In1.Cu" signal "GND")
		(6 "In2.Cu" signal "IN1")
		(8 "In3.Cu" signal "GND1")
		(10 "In4.Cu" signal "IN2")
		(12 "In5.Cu" signal "VCC")
		(14 "In6.Cu" signal "VCC1")
		(16 "In7.Cu" signal "IN3")
		(18 "In8.Cu" signal "GND2")
		(20 "In9.Cu" signal "IN4")
		(22 "In10.Cu" signal "GND3")
		(2 "B.Cu" signal "BOTTOM")
		(9 "F.Adhes" user "F.Adhesive")
		(11 "B.Adhes" user "B.Adhesive")
		(13 "F.Paste" user "Package Geometry/Pastemask Top")
		(15 "B.Paste" user "Package Geometry/Pastemask Bottom")
		(5 "F.SilkS" user "Ref Des/Silkscreen Top")
		(7 "B.SilkS" user "Ref Des/Silkscreen Bottom")
		(1 "F.Mask" user "Board Geometry/Soldermask Top")
		(3 "B.Mask" user "Board Geometry/Soldermask Bottom")
		(17 "Dwgs.User" user "User.Drawings")
		(19 "Cmts.User" user "User.Comments")
		(21 "Eco1.User" user "User.Eco1")
		(23 "Eco2.User" user "User.Eco2")
		(25 "Edge.Cuts" user "Board Geometry/Outline")
		(27 "Margin" user)
		(31 "F.CrtYd" user "Package Geometry/Place Bound Top")
		(29 "B.CrtYd" user "Package Geometry/Place Bound Bottom")
		(35 "F.Fab" user "Ref Des/Assembly Top")
		(33 "B.Fab" user "Ref Des/Assembly Bottom")
	)
	(footprint ""
		(layer "B.Cu")
		(at 72.621394 -72.047608 -90)
		(property "Reference" "R684"
			(at 0 0 90)
			(layer "B.SilkS")
			(hide yes)
			(effects
				(font
					(size 1.27 1.27)
				)
				(justify mirror)
			)
		)
		(property "Value" ""
			(at 0 0 90)
			(layer "B.Fab")
			(effects
				(font
					(size 1.27 1.27)
				)
				(justify mirror)
			)
		)
		(duplicate_pad_numbers_are_jumpers no)
		(fp_line
			(start -0.7874 0.4064)
			(end 0.7874 0.4064)
			(stroke
				(width 0.1524)
				(type default)
			)
			(layer "B.SilkS")
		)
		(fp_line
			(start 0.7874 0.4064)
			(end 0.7874 -0.4064)
			(stroke
				(width 0.1524)
				(type default)
			)
			(layer "B.SilkS")
		)
		(fp_line
			(start -0.7874 -0.4064)
			(end -0.7874 0.4064)
			(stroke
				(width 0.1524)
				(type default)
			)
			(layer "B.SilkS")
		)
		(fp_line
			(start 0.7874 -0.4064)
			(end -0.7874 -0.4064)
			(stroke
				(width 0.1524)
				(type default)
			)
			(layer "B.SilkS")
		)
		(fp_line
			(start -0.67945 0.3048)
			(end -0.120396 0.3048)
			(stroke
				(width 0.1)
				(type default)
			)
			(layer "B.Fab")
		)
		(fp_line
			(start -0.120396 0.3048)
			(end -0.120396 0.2794)
			(stroke
				(width 0.1)
				(type default)
			)
			(layer "B.Fab")
		)
		(fp_line
			(start 0.12065 0.3048)
			(end 0.67945 0.3048)
			(stroke
				(width 0.1)
				(type default)
			)
			(layer "B.Fab")
		)
		(fp_line
			(start 0.67945 0.3048)
			(end 0.67945 -0.305054)
			(stroke
				(width 0.1)
				(type default)
			)
			(layer "B.Fab")
		)
		(fp_line
			(start -0.120396 0.2794)
			(end 0.12065 0.2794)
			(stroke
				(width 0.1)
				(type default)
			)
			(layer "B.Fab")
		)
		(fp_line
			(start 0.12065 0.2794)
			(end 0.12065 0.3048)
			(stroke
				(width 0.1)
				(type default)
			)
			(layer "B.Fab")
		)
		(fp_line
			(start -0.12065 -0.2794)
			(end -0.12065 -0.3048)
			(stroke
				(width 0.1)
				(type default)
			)
			(layer "B.Fab")
		)
		(fp_line
			(start 0.12065 -0.2794)
			(end -0.12065 -0.2794)
			(stroke
				(width 0.1)
				(type default)
			)
			(layer "B.Fab")
		)
		(fp_line
			(start -0.67945 -0.3048)
			(end -0.67945 0.3048)
			(stroke
				(width 0.1)
				(type default)
			)
			(layer "B.Fab")
		)
		(fp_line
			(start -0.12065 -0.3048)
			(end -0.67945 -0.3048)
			(stroke
				(width 0.1)
				(type default)
			)
			(layer "B.Fab")
		)
		(fp_line
			(start 0.12065 -0.305054)
			(end 0.12065 -0.2794)
			(stroke
				(width 0.1)
				(type default)
			)
			(layer "B.Fab")
		)
		(fp_line
			(start 0.67945 -0.305054)
			(end 0.12065 -0.305054)
			(stroke
				(width 0.1)
				(type default)
			)
			(layer "B.Fab")
		)
		(pad "1" smd circle
			(at 0.40005 0 90)
			(size 0 0)
			(layers "B.Cu" "B.Mask" "B.Paste")
			(net "BMC_EMMC_WP_N")
		)
		(pad "2" smd circle
			(at -0.40005 0 90)
			(size 0 0)
			(layers "B.Cu" "B.Mask" "B.Paste")
			(net "GND")
		)
	)
	(footprint ""
		(layer "B.Cu")
		(at 44.38396 -34.637726 90)
		(property "Reference" "R139"
			(at 0 0 90)
			(layer "B.SilkS")
			(hide yes)
			(effects
				(font
					(size 1.27 1.27)
				)
				(justify mirror)
			)
		)
		(property "Value" ""
			(at 0 0 90)
			(layer "B.Fab")
			(effects
				(font
					(size 1.27 1.27)
				)
				(justify mirror)
			)
		)
		(duplicate_pad_numbers_are_jumpers no)
		(fp_line
			(start 0.7874 -0.4064)
			(end -0.7874 -0.4064)
			(stroke
				(width 0.1524)
				(type default)
			)
			(layer "B.SilkS")
		)
		(fp_line
			(start -0.7874 -0.4064)
			(end -0.7874 0.4064)
			(stroke
				(width 0.1524)
				(type default)
			)
			(layer "B.SilkS")
		)
		(fp_line
			(start 0.7874 0.4064)
			(end 0.7874 -0.4064)
			(stroke
				(width 0.1524)
				(type default)
			)
			(layer "B.SilkS")
		)
		(fp_line
			(start -0.7874 0.4064)
			(end 0.7874 0.4064)
			(stroke
				(width 0.1524)
				(type default)
			)
			(layer "B.SilkS")
		)
		(fp_line
			(start 0.67945 -0.305054)
			(end 0.12065 -0.305054)
			(stroke
				(width 0.1)
				(type default)
			)
			(layer "B.Fab")
		)
		(fp_line
			(start 0.12065 -0.305054)
			(end 0.12065 -0.2794)
			(stroke
				(width 0.1)
				(type default)
			)
			(layer "B.Fab")
		)
		(fp_line
			(start -0.12065 -0.3048)
			(end -0.67945 -0.3048)
			(stroke
				(width 0.1)
				(type default)
			)
			(layer "B.Fab")
		)
		(fp_line
			(start -0.67945 -0.3048)
			(end -0.67945 0.3048)
			(stroke
				(width 0.1)
				(type default)
			)
			(layer "B.Fab")
		)
		(fp_line
			(start 0.12065 -0.2794)
			(end -0.12065 -0.2794)
			(stroke
				(width 0.1)
				(type default)
			)
			(layer "B.Fab")
		)
		(fp_line
			(start -0.12065 -0.2794)
			(end -0.12065 -0.3048)
			(stroke
				(width 0.1)
				(type default)
			)
			(layer "B.Fab")
		)
		(fp_line
			(start 0.12065 0.2794)
			(end 0.12065 0.3048)
			(stroke
				(width 0.1)
				(type default)
			)
			(layer "B.Fab")
		)
		(fp_line
			(start -0.120396 0.2794)
			(end 0.12065 0.2794)
			(stroke
				(width 0.1)
				(type default)
			)
			(layer "B.Fab")
		)
		(fp_line
			(start 0.67945 0.3048)
			(end 0.67945 -0.305054)
			(stroke
				(width 0.1)
				(type default)
			)
			(layer "B.Fab")
		)
		(fp_line
			(start 0.12065 0.3048)
			(end 0.67945 0.3048)
			(stroke
				(width 0.1)
				(type default)
			)
			(layer "B.Fab")
		)
		(fp_line
			(start -0.120396 0.3048)
			(end -0.120396 0.2794)
			(stroke
				(width 0.1)
				(type default)
			)
			(layer "B.Fab")
		)
		(fp_line
			(start -0.67945 0.3048)
			(end -0.120396 0.3048)
			(stroke
				(width 0.1)
				(type default)
			)
			(layer "B.Fab")
		)
		(pad "1" smd circle
			(at 0.40005 0 270)
			(size 0 0)
			(layers "B.Cu" "B.Mask" "B.Paste")
			(net "SMB_BMC_MM4_R_SDA")
		)
		(pad "2" smd circle
			(at -0.40005 0 270)
			(size 0 0)
			(layers "B.Cu" "B.Mask" "B.Paste")
			(net "SMB_BMC_MM4_SDA")
		)
	)
)
